# BASEBOARD_FAB2 (Tioga Pass) — schematic netlist excerpt (pin names and nets, part order shuffled) for the footprints in the layout excerpt that follows; sources: Cadence DE-HDL packaged netlist, KiCad conversion of Wiwynn_Tioga_Pass_MB.brd

EU1D2  ADM1278  IC  pkg SM  page 199
  PSET  = A_HSC_PSET
  VCAP  = A_HSC_VCAP
  ISET  = A_HSC_ISET
  ISTART  = A_HSC_ISTART
  TIMER  = A_HSC_TIMER
  FAULT_N  = IRQ_HSC_FAULT_R_N
  ADR1  = FM_P12V_HSC_ADR1
  ADR2  = FM_P12V_HSC_ADR2
  SPISS_N  = TP_HSC_SPISSN
  MCLK  = TP_HSC_MCLK
  MDAT  = TP_HSC_MDAT
  ENABLE  = FM_P12V_HOTSWAP0_EN
  GPO1_ALERT1_N_CONV  = IRQ_SML1_PMBUS_ALERT_R_N
  GPO2_ALERT2_N  = TP_HSC_ALERT2_N
  SDA  = SMB_3V3SB_HSC_SDA_R
  SCL  = SMB_3V3SB_HSC_SCL_R
  RETRY_N  = PD_HSC_RETRY_N
  PWRGD  = PWRGD_P12V_R
  CSOUT  = A_HSC_CSOUT
  VOUT  = A_HSC_VOUT
  PWGIN  = A_HSC_PWGIN
  GND  = AGND_HSC
  PGND  = GND
  GATE  = A_HSC_GATE
  TEMP  = A_HSC_TEMP
  MON  = A_HSC_MON
  HSN  = A_HSC_HSN
  HSP  = A_HSC_HSP
  MOP  = A_HSC_MOP
  VCC  = P12V_HSC_VCC
  UV  = A_HSC_UV
  OV  = A_HSC_OV
  EP  = AGND_HSC

(kicad_pcb
	(version 20260206)
	(generator "pcbnew")
	(generator_version "10.0")
	(general
		(thickness 1.6)
		(legacy_teardrops no)
	)
	(paper "A4")
	(title_block
		(title "Wiwynn_Tioga_Pass_MB.brd")
		(comment 1 "Tioga Pass / footprint 2252 of 4770 (EU1D2), pads 1-17 of 33")
	)
	(layers
		(0 "F.Cu" signal "TOP")
		(4 "In1.Cu" signal "L2GND")
		(6 "In2.Cu" signal "L3")
		(8 "In3.Cu" signal "L4GND")
		(10 "In4.Cu" signal "L5")
		(12 "In5.Cu" signal "L6GND")
		(14 "In6.Cu" signal "L7VCC")
		(16 "In7.Cu" signal "L8VCC")
		(18 "In8.Cu" signal "L9GND")
		(20 "In9.Cu" signal "L10")
		(22 "In10.Cu" signal "L11GND")
		(24 "In11.Cu" signal "L12")
		(26 "In12.Cu" signal "L13GND")
		(2 "B.Cu" signal "BOTTOM")
		(9 "F.Adhes" user "F.Adhesive")
		(11 "B.Adhes" user "B.Adhesive")
		(13 "F.Paste" user "Package Geometry/Pastemask Top")
		(15 "B.Paste" user "Package Geometry/Pastemask Bottom")
		(5 "F.SilkS" user "Ref Des/Silkscreen Top")
		(7 "B.SilkS" user "Ref Des/Silkscreen Bottom")
		(1 "F.Mask" user "Board Geometry/Soldermask Top")
		(3 "B.Mask" user "Board Geometry/Soldermask Bottom")
		(17 "Dwgs.User" user "User.Drawings")
		(19 "Cmts.User" user "User.Comments")
		(21 "Eco1.User" user "User.Eco1")
		(23 "Eco2.User" user "User.Eco2")
		(25 "Edge.Cuts" user "Board Geometry/Outline")
		(27 "Margin" user)
		(31 "F.CrtYd" user "Package Geometry/Place Bound Top")
		(29 "B.CrtYd" user "Package Geometry/Place Bound Bottom")
		(35 "F.Fab" user "Ref Des/Assembly Top")
		(33 "B.Fab" user "Ref Des/Assembly Bottom")
	)
	(footprint ""
		(layer "F.Cu")
		(at 18.161 -75.692 180)
		(property "Reference" "EU1D2"
			(at -0.127 -3.58267 0)
			(unlocked yes)
			(layer "F.SilkS")
			(effects
				(font
					(size 0.7874 0.5842)
					(thickness 0.1524)
				)
			)
		)
		(property "Value" ""
			(at 0 0 180)
			(layer "F.Fab")
			(effects
				(font
					(size 1.27 1.27)
				)
			)
		)
		(duplicate_pad_numbers_are_jumpers no)
		(pad "1" smd custom
			(at -2.3495 -1.75133 180)
			(size 0.0762 0.0762)
			(layers "F.Cu" "F.Mask" "F.Paste")
			(net "A_HSC_PSET")
			(options
				(clearance outline)
				(anchor circle)
			)
			(primitives
				(gr_poly
					(pts
						(xy -0.3556 0.1524) (xy -0.3556 -0.1524)
						(arc
							(start 0.2032 -0.1524)
							(mid 0.3556 0)
							(end 0.2032 0.1524)
						)
					)
					(width 0)
					(fill yes)
				)
			)
		)
		(pad "2" smd custom
			(at -2.3495 -1.25095 180)
			(size 0.0762 0.0762)
			(layers "F.Cu" "F.Mask" "F.Paste")
			(net "A_HSC_VCAP")
			(options
				(clearance outline)
				(anchor circle)
			)
			(primitives
				(gr_poly
					(pts
						(xy -0.3556 0.1524) (xy -0.3556 -0.1524)
						(arc
							(start 0.2032 -0.1524)
							(mid 0.3556 0)
							(end 0.2032 0.1524)
						)
					)
					(width 0)
					(fill yes)
				)
			)
		)
		(pad "3" smd custom
			(at -2.3495 -0.75057 180)
			(size 0.0762 0.0762)
			(layers "F.Cu" "F.Mask" "F.Paste")
			(net "A_HSC_ISET")
			(options
				(clearance outline)
				(anchor circle)
			)
			(primitives
				(gr_poly
					(pts
						(xy -0.3556 0.1524) (xy -0.3556 -0.1524)
						(arc
							(start 0.2032 -0.1524)
							(mid 0.3556 0)
							(end 0.2032 0.1524)
						)
					)
					(width 0)
					(fill yes)
				)
			)
		)
		(pad "4" smd custom
			(at -2.3495 -0.25019 180)
			(size 0.0762 0.0762)
			(layers "F.Cu" "F.Mask" "F.Paste")
			(net "A_HSC_ISTART")
			(options
				(clearance outline)
				(anchor circle)
			)
			(primitives
				(gr_poly
					(pts
						(xy -0.3556 0.1524) (xy -0.3556 -0.1524)
						(arc
							(start 0.2032 -0.1524)
							(mid 0.3556 0)
							(end 0.2032 0.1524)
						)
					)
					(width 0)
					(fill yes)
				)
			)
		)
		(pad "5" smd custom
			(at -2.3495 0.25019 180)
			(size 0.0762 0.0762)
			(layers "F.Cu" "F.Mask" "F.Paste")
			(net "A_HSC_TIMER")
			(options
				(clearance outline)
				(anchor circle)
			)
			(primitives
				(gr_poly
					(pts
						(xy -0.3556 0.1524) (xy -0.3556 -0.1524)
						(arc
							(start 0.2032 -0.1524)
							(mid 0.3556 0)
							(end 0.2032 0.1524)
						)
					)
					(width 0)
					(fill yes)
				)
			)
		)
		(pad "6" smd custom
			(at -2.3495 0.75057 180)
			(size 0.0762 0.0762)
			(layers "F.Cu" "F.Mask" "F.Paste")
			(net "IRQ_HSC_FAULT_R_N")
			(options
				(clearance outline)
				(anchor circle)
			)
			(primitives
				(gr_poly
					(pts
						(xy -0.3556 0.1524) (xy -0.3556 -0.1524)
						(arc
							(start 0.2032 -0.1524)
							(mid 0.3556 0)
							(end 0.2032 0.1524)
						)
					)
					(width 0)
					(fill yes)
				)
			)
		)
		(pad "7" smd custom
			(at -2.3495 1.25095 180)
			(size 0.0762 0.0762)
			(layers "F.Cu" "F.Mask" "F.Paste")
			(net "FM_P12V_HSC_ADR1")
			(options
				(clearance outline)
				(anchor circle)
			)
			(primitives
				(gr_poly
					(pts
						(xy -0.3556 0.1524) (xy -0.3556 -0.1524)
						(arc
							(start 0.2032 -0.1524)
							(mid 0.3556 0)
							(end 0.2032 0.1524)
						)
					)
					(width 0)
					(fill yes)
				)
			)
		)
		(pad "8" smd custom
			(at -2.3495 1.75133 180)
			(size 0.0762 0.0762)
			(layers "F.Cu" "F.Mask" "F.Paste")
			(net "FM_P12V_HSC_ADR2")
			(options
				(clearance outline)
				(anchor circle)
			)
			(primitives
				(gr_poly
					(pts
						(xy -0.3556 0.1524) (xy -0.3556 -0.1524)
						(arc
							(start 0.2032 -0.1524)
							(mid 0.3556 0)
							(end 0.2032 0.1524)
						)
					)
					(width 0)
					(fill yes)
				)
			)
		)
		(pad "9" smd custom
			(at -1.75133 2.3495 180)
			(size 0.0762 0.0762)
			(layers "F.Cu" "F.Mask" "F.Paste")
			(net "TP_HSC_SPISSN")
			(options
				(clearance outline)
				(anchor circle)
			)
			(primitives
				(gr_poly
					(pts
						(xy 0.1524 0.3556) (xy -0.1524 0.3556)
						(arc
							(start -0.1524 -0.2032)
							(mid 0 -0.3556)
							(end 0.1524 -0.2032)
						)
					)
					(width 0)
					(fill yes)
				)
			)
		)
		(pad "10" smd custom
			(at -1.25095 2.3495 180)
			(size 0.0762 0.0762)
			(layers "F.Cu" "F.Mask" "F.Paste")
			(net "TP_HSC_MCLK")
			(options
				(clearance outline)
				(anchor circle)
			)
			(primitives
				(gr_poly
					(pts
						(xy 0.1524 0.3556) (xy -0.1524 0.3556)
						(arc
							(start -0.1524 -0.2032)
							(mid 0 -0.3556)
							(end 0.1524 -0.2032)
						)
					)
					(width 0)
					(fill yes)
				)
			)
		)
		(pad "11" smd custom
			(at -0.75057 2.3495 180)
			(size 0.0762 0.0762)
			(layers "F.Cu" "F.Mask" "F.Paste")
			(net "TP_HSC_MDAT")
			(options
				(clearance outline)
				(anchor circle)
			)
			(primitives
				(gr_poly
					(pts
						(xy 0.1524 0.3556) (xy -0.1524 0.3556)
						(arc
							(start -0.1524 -0.2032)
							(mid 0 -0.3556)
							(end 0.1524 -0.2032)
						)
					)
					(width 0)
					(fill yes)
				)
			)
		)
		(pad "12" smd custom
			(at -0.25019 2.3495 180)
			(size 0.0762 0.0762)
			(layers "F.Cu" "F.Mask" "F.Paste")
			(net "FM_P12V_HOTSWAP0_EN")
			(options
				(clearance outline)
				(anchor circle)
			)
			(primitives
				(gr_poly
					(pts
						(xy 0.1524 0.3556) (xy -0.1524 0.3556)
						(arc
							(start -0.1524 -0.2032)
							(mid 0 -0.3556)
							(end 0.1524 -0.2032)
						)
					)
					(width 0)
					(fill yes)
				)
			)
		)
		(pad "13" smd custom
			(at 0.25019 2.3495 180)
			(size 0.0762 0.0762)
			(layers "F.Cu" "F.Mask" "F.Paste")
			(net "IRQ_SML1_PMBUS_ALERT_R_N")
			(options
				(clearance outline)
				(anchor circle)
			)
			(primitives
				(gr_poly
					(pts
						(xy 0.1524 0.3556) (xy -0.1524 0.3556)
						(arc
							(start -0.1524 -0.2032)
							(mid 0 -0.3556)
							(end 0.1524 -0.2032)
						)
					)
					(width 0)
					(fill yes)
				)
			)
		)
		(pad "14" smd custom
			(at 0.75057 2.3495 180)
			(size 0.0762 0.0762)
			(layers "F.Cu" "F.Mask" "F.Paste")
			(net "TP_HSC_ALERT2_N")
			(options
				(clearance outline)
				(anchor circle)
			)
			(primitives
				(gr_poly
					(pts
						(xy 0.1524 0.3556) (xy -0.1524 0.3556)
						(arc
							(start -0.1524 -0.2032)
							(mid 0 -0.3556)
							(end 0.1524 -0.2032)
						)
					)
					(width 0)
					(fill yes)
				)
			)
		)
		(pad "15" smd custom
			(at 1.25095 2.3495 180)
			(size 0.0762 0.0762)
			(layers "F.Cu" "F.Mask" "F.Paste")
			(net "SMB_3V3SB_HSC_SDA_R")
			(options
				(clearance outline)
				(anchor circle)
			)
			(primitives
				(gr_poly
					(pts
						(xy 0.1524 0.3556) (xy -0.1524 0.3556)
						(arc
							(start -0.1524 -0.2032)
							(mid 0 -0.3556)
							(end 0.1524 -0.2032)
						)
					)
					(width 0)
					(fill yes)
				)
			)
		)
		(pad "16" smd custom
			(at 1.75133 2.3495 180)
			(size 0.0762 0.0762)
			(layers "F.Cu" "F.Mask" "F.Paste")
			(net "SMB_3V3SB_HSC_SCL_R")
			(options
				(clearance outline)
				(anchor circle)
			)
			(primitives
				(gr_poly
					(pts
						(xy 0.1524 0.3556) (xy -0.1524 0.3556)
						(arc
							(start -0.1524 -0.2032)
							(mid 0 -0.3556)
							(end 0.1524 -0.2032)
						)
					)
					(width 0)
					(fill yes)
				)
			)
		)
		(pad "17" smd custom
			(at 2.3495 1.75133 180)
			(size 0.0762 0.0762)
			(layers "F.Cu" "F.Mask" "F.Paste")
			(net "PD_HSC_RETRY_N")
			(options
				(clearance outline)
				(anchor circle)
			)
			(primitives
				(gr_poly
					(pts
						(xy 0.3556 -0.1524) (xy 0.3556 0.1524)
						(arc
							(start -0.2032 0.1524)
							(mid -0.3556 0)
							(end -0.2032 -0.1524)
						)
					)
					(width 0)
					(fill yes)
				)
			)
		)
	)
)
